5
5
4
4
3
3
2
2
1
1
D D
C C
B B
A A
Grand Teton HPDB
Project Name: Grand Teton HPDBPCB Number: PCB REV: FPCB Size: 475 * 172.3 (mm)PCB Layer: 10LAST UPDATE: 2022/12/27
COVER PAGE
SizeDoc NumberRevDate: SheetofReviewerDesignerDepartmentProject
Page TitleBU9<Doc> AB Friday, August 25, 2023<Designer><Reviewer> 1 32<Title><Page Title>SizeDoc NumberRevDate: SheetofReviewerDesignerDepartmentProject
Page TitleBU9<Doc> AB Friday, August 25, 2023<Designer><Reviewer> 1 32<Title><Page Title>SizeDoc NumberRevDate: SheetofReviewerDesignerDepartmentProject
Page TitleBU9<Doc> AB Friday, August 25, 2023<Designer><Reviewer> 1 32<Title><Page Title>



5
5
4
4
3
3
2
2
1
1
D D
C C
B B
A A
INDEX
001 COVER PAGE002 PAGE INDEX003 BOARD BLOCK DIAGRAM004 I2C BLOCK DIAGRAM005 POWER BLOCK DIAGRAM006 POWER SEQUENCE DIAGRAM007 I2C ISOLATION008 I2C MUX009 P52V VOLTAGE MONITOR010 P52V VOLTAGE MONITOR 2011 POWER GOOD LEDs012 IOEXP013 FRU014 TO GPU BOARD CONN015 TO V_PDB CONN016 48V POWER CONN017 TO FAN BP CONN018 ECAP_P48V_1019 ECAP_P48V_2020 HOT SWAP P52V_HS1021 HOT SWAP P52V_HS1_2022 HOT SWAP P52V_HS2023 HOT SWAP P52V_HS2_2024 GPU HSC EN BUFFER025 P3V3_AUX
PAGE INDEX
026 P12V CURRENT LIMIT027 MOSFET_RSHUNT_1028 MOSFET_RSHUNT_2029 LOSS COUPON030 DUMMY SYMBOLS031 SCREW HOLES032 TDR
SizeDoc NumberRevDate: SheetofReviewerDesignerDepartmentProject
Page TitleBU9<Doc> AB Thursday, August 24, 2023<Designer><Reviewer> 2 32<Title><Page Title>SizeDoc NumberRevDate: SheetofReviewerDesignerDepartmentProject
Page TitleBU9<Doc> AB Thursday, August 24, 2023<Designer><Reviewer> 2 32<Title><Page Title>SizeDoc NumberRevDate: SheetofReviewerDesignerDepartmentProject
Page TitleBU9<Doc> AB Thursday, August 24, 2023<Designer><Reviewer> 2 32<Title><Page Title>



5
5
4
4
3
3
2
2
1
1
D D
C C
B B
A A
BOARD BLOCK DIAGRAM SizeDoc NumberRevDate: SheetofReviewerDesignerDepartmentProject
Page TitleBU9<Doc> AC Thursday, August 24, 2023<Designer><Reviewer> 3 32<Title><Page Title>SizeDoc NumberRevDate: SheetofReviewerDesignerDepartmentProject
Page TitleBU9<Doc> AC Thursday, August 24, 2023<Designer><Reviewer> 3 32<Title><Page Title>SizeDoc NumberRevDate: SheetofReviewerDesignerDepartmentProject
Page TitleBU9<Doc> AC Thursday, August 24, 2023<Designer><Reviewer> 3 32<Title><Page Title>



5
5
4
4
3
3
2
2
1
1
D D
C C
B B
A A
I2C BLOCK DIAGRAM SizeDoc NumberRevDate: SheetofReviewerDesignerDepartmentProject
Page TitleBU9<Doc> AC Thursday, August 24, 2023<Designer><Reviewer> 4 32<Title><Page Title>SizeDoc NumberRevDate: SheetofReviewerDesignerDepartmentProject
Page TitleBU9<Doc> AC Thursday, August 24, 2023<Designer><Reviewer> 4 32<Title><Page Title>SizeDoc NumberRevDate: SheetofReviewerDesignerDepartmentProject
Page TitleBU9<Doc> AC Thursday, August 24, 2023<Designer><Reviewer> 4 32<Title><Page Title>



5
5
4
4
3
3
2
2
1
1
D D
C C
B B
A A
POWER BLOCK DIAGRAM SizeDoc NumberRevDate: SheetofReviewerDesignerDepartmentProject
Page TitleBU9<Doc> AC Thursday, August 24, 2023<Designer><Reviewer> 5 32<Title><Page Title>SizeDoc NumberRevDate: SheetofReviewerDesignerDepartmentProject
Page TitleBU9<Doc> AC Thursday, August 24, 2023<Designer><Reviewer> 5 32<Title><Page Title>SizeDoc NumberRevDate: SheetofReviewerDesignerDepartmentProject
Page TitleBU9<Doc> AC Thursday, August 24, 2023<Designer><Reviewer> 5 32<Title><Page Title>



5
5
4
4
3
3
2
2
1
1
D D
C C
B B
A A
006 POWER SEQUENCE DIAGRAM SizeDoc NumberRevDate: SheetofReviewerDesignerDepartmentProject
Page TitleBU9<Doc> AC Thursday, August 24, 2023<Designer><Reviewer> 6 32<Title><Page Title>SizeDoc NumberRevDate: SheetofReviewerDesignerDepartmentProject
Page TitleBU9<Doc> AC Thursday, August 24, 2023<Designer><Reviewer> 6 32<Title><Page Title>SizeDoc NumberRevDate: SheetofReviewerDesignerDepartmentProject
Page TitleBU9<Doc> AC Thursday, August 24, 2023<Designer><Reviewer> 6 32<Title><Page Title>



5
5
4
4
3
3
2
2
1
1
D D
C C
B B
A A
 I2C ISOLATION
CAD Note: Place Resistors near LTC4307
From MB
CAD Note: Place Resistors near LTC4307
From MB
MB BMC I2C
PWRGD_P3V3_AUX_MB_BUF7,15,24SMB_PDB_SCL15 SMB_PDB_MISC_SCL_R1 8,13SMB_PDB_SDA15 SMB_PDB_MISC_SDA 8,12,13PWRGD_P3V3_AUX_MB_BUF7,15,24SMB_P52V_SCL15 SMB_P52V_PDB_SCL 20,21,22,23,27SMB_P52V_SDA15 SMB_P52V_PDB_SDA 20,21,22,23,27SMB_PDB_MISC_SCL 12P3V3_AUXP3V3_AUXP3V3_AUXP3V3_AUXP3V3_AUXP3V3_AUX
SizeDoc NumberRevDate: SheetofReviewerDesignerDepartmentProject
Page TitleBU9<Doc> ACustom Thursday, August 24, 2023<Designer><Reviewer> 7 32<Title><Page Title>SizeDoc NumberRevDate: SheetofReviewerDesignerDepartmentProject
Page TitleBU9<Doc> ACustom Thursday, August 24, 2023<Designer><Reviewer> 7 32<Title><Page Title>SizeDoc NumberRevDate: SheetofReviewerDesignerDepartmentProject
Page TitleBU9<Doc> ACustom Thursday, August 24, 2023<Designer><Reviewer> 7 32<Title><Page Title>
R12 331% R0402-02011/16WR94.7KR0402-02015%1/16WNIR14 05% R0402-0201 1/16WC10.1UF10%16VC0402-0201X7RR11 331% R0402-02011/16WU1LTC4307ENABLE1SCL_IN3SDA_IN6GND4VCC8SCL_OUT2SDA_OUT7READY5R10 05%R0402-0201 1/16WNIR6 05% R0402-0201NI 1/16WR110KR04021%1/16WC20.1UF10%16VC0402-0201X7RNIR5 331% R0402-02011/16WR210KR04021%1/16WR7 05% R0402-0201NI 1/16WU2LTC4307NIENABLE1SCL_IN3SDA_IN6GND4VCC8SCL_OUT2SDA_OUT7READY5R13 05% R0402-0201 1/16WR84.7KR0402-02015%1/16WNIR4 331% R0402-02011/16WR389 331% R0402-02011/16WR3 05%R0402-0201 1/16WMB_MISC_I2C_ENSMB_PDB_SCLSMB_PDB_MISC_SCL_RSMB_PDB_MISC_SCL_R1SMB_PDB_SDASMB_PDB_MISC_SDA_RSMB_PDB_MISC_SDAMB_P52V_I2C_ENSMB_P52V_SCLSMB_P52V_PDB_SCL_RSMB_P52V_PDB_SCLSMB_P52V_SDASMB_P52V_PDB_SDA_RSMB_P52V_PDB_SDANC_U1_READYNC_U2_READY



5
5
4
4
3
3
2
2
1
1
D D
C C
B B
A A
I2C MUX
ADDRESS 0XE2[1 1 1 0 0 A1 A0 0]
SMB_PDB_MISC_SCL_R17,13SMB_PDB_FAN_0_SCL 17SMB_PDB_MISC_SDA7,12,13SMB_PDB_FAN_0_SDA 17SMB_PDB_FAN_1_SCL 17SMB_PDB_FAN_1_SDA 17RST_SMB_PDB_BUF_N15,17P3V3_AUXP3V3_AUXP3V3_AUXP3V3_AUXP3V3_AUXP3V3_AUXP3V3_AUXP3V3_AUXP3V3_AUX
SizeDoc NumberRevDate: SheetofReviewerDesignerDepartmentProject
Page TitleBU9<Doc> ACustom Thursday, August 24, 2023<Designer><Reviewer> 8 32<Title><Page Title>SizeDoc NumberRevDate: SheetofReviewerDesignerDepartmentProject
Page TitleBU9<Doc> ACustom Thursday, August 24, 2023<Designer><Reviewer> 8 32<Title><Page Title>SizeDoc NumberRevDate: SheetofReviewerDesignerDepartmentProject
Page TitleBU9<Doc> ACustom Thursday, August 24, 2023<Designer><Reviewer> 8 32<Title><Page Title>
R234.7KR0402-02015%1/16WR32910KR04021%1/16WR164.7KR0402-02015%1/16WR33010KR04021%1/16WR32810KR04021%1/16WR224.7KR0402-02015%1/16WNIR19 331% R0402-02011/16WR33110KR04021%1/16WR25100<Part Number>NIR24100<Part Number>C30.1UF10%16VC0402-0201X7RU18PCA9543ADA01A12RESET#3SC110SD05SC06INT0#4INT1#8SD19VSS7SCL12SDA13INT#11VDD14R20 331% R0402-02011/16WR154.7KR0402-02015%1/16WSMB_FAN_MUX_SCLSMB_FAN_MUX_SDATP_9543_FAN_INT_NPU_9543_0_FANPU_9543_1_FANPD_9543_FAN_A1PD_9543_FAN_A0



5
5
4
4
3
3
2
2
1
1
D D
C C
B B
A A
P52V VOLTAGE MONITOR
SizeDoc NumberRevDate: SheetofReviewerDesignerDepartmentProject
Page TitleBU9<Doc> AB Thursday, August 24, 2023<Designer><Reviewer> 9 32<Title><Page Title>SizeDoc NumberRevDate: SheetofReviewerDesignerDepartmentProject
Page TitleBU9<Doc> AB Thursday, August 24, 2023<Designer><Reviewer> 9 32<Title><Page Title>SizeDoc NumberRevDate: SheetofReviewerDesignerDepartmentProject
Page TitleBU9<Doc> AB Thursday, August 24, 2023<Designer><Reviewer> 9 32<Title><Page Title>



5
5
4
4
3
3
2
2
1
1
D D
C C
B B
A A
P52V VOLTAGE MONITOR 2 SizeDoc NumberRevDate: SheetofReviewerDesignerDepartmentProject
Page TitleBU9<Doc> AB Thursday, August 24, 2023<Designer><Reviewer> 10 32<Title><Page Title>SizeDoc NumberRevDate: SheetofReviewerDesignerDepartmentProject
Page TitleBU9<Doc> AB Thursday, August 24, 2023<Designer><Reviewer> 10 32<Title><Page Title>SizeDoc NumberRevDate: SheetofReviewerDesignerDepartmentProject
Page TitleBU9<Doc> AB Thursday, August 24, 2023<Designer><Reviewer> 10 32<Title><Page Title>



5
5
4
4
3
3
2
2
1
1
D D
C C
B B
A A
POWER GOOD LEDs
P52V_2_LEDP52V_1_LED
P3V3_AUX_LED
P52V_HS1P52V_HS2P3V3_AUX
SizeDoc NumberRevDate: SheetofReviewerDesignerDepartmentProject
Page TitleBU9<Doc> ACustom Thursday, August 24, 2023<Designer><Reviewer> 11 32<Title><Page Title>SizeDoc NumberRevDate: SheetofReviewerDesignerDepartmentProject
Page TitleBU9<Doc> ACustom Thursday, August 24, 2023<Designer><Reviewer> 11 32<Title><Page Title>SizeDoc NumberRevDate: SheetofReviewerDesignerDepartmentProject
Page TitleBU9<Doc> ACustom Thursday, August 24, 2023<Designer><Reviewer> 11 32<Title><Page Title>
R592975<Part Number>1/16W1%R441K5%1/4WR1206XNR411K5%1/4WR1206XND2LED_BLUEAC
D6LED_BLUEAC R431K5%1/4WR1206XNR461K5%1/4WR1206XNR451K5%1/4WR1206XNR421K5%1/4WR1206XNR391K5%1/4WR1206XNR381K5%1/4WR1206XN
D1LED_BLUEAC
R401K5%1/4WR1206XNR471K5%1/4WR1206XN
LED_D1_R5LED_D1_R1LED_D1_R2LED_D1_R3LED_D1_R4
LED_D2_R1LED_D2_R2LED_D2_R3LED_D2_R4LED_D2_R5
LED_D6_R1



5
5
4
4
3
3
2
2
1
1
D D
C C
B B
A A
IOEXP
ADDRESS 0X46[0 1 0 0 A2 A1 A0 0]
BOARD_ID_2
0PO
STAGE
EVT
BOARD ID
BOARD_ID_1
0 0
BOARD_ID_0
0 0 1
EVT2 0 1 0
LTC4287
ADM1272
HSC
SKU ID
SKU_ID_2
0
1
DVT 0 1 1
ADDRESS 0X4A[0 1 0 0 A2 A1 A0 0]
DVT2 1 0 0
PVT 1 1 0
PRSNT_FAN_BP0_N 17PRSNT_FAN_BP1_N 17SMB_PDB_MISC_SDA7,8,12,13SMB_PDB_MISC_SCL7,12P52V_HS1_FLT 20,21P52V_HS2_FLT 22,23PWRGD_P52V_HS1_PG 15,21PWRGD_P52V_HS2_PG 15,23PWRGD_P12V_FAN_LED 26SMB_PDB_MISC_SDA7,8,12,13SMB_PDB_MISC_SCL7,12FM_HS1_EN_BUSBAR_BUF 27FM_HS1_EN_FUSE_BUF 27FM_HS2_EN_BUSBAR_BUF 28FM_HS2_EN_FUSE_BUF 28P3V3_AUXP3V3_AUXP3V3_AUXP3V3_AUXP3V3_AUXP3V3_AUXP3V3_AUXP3V3_AUXP3V3_AUXP3V3_AUXP3V3_AUX
P3V3_AUXP3V3_AUXP3V3_AUXP3V3_AUXP3V3_AUX
SizeDoc NumberRevDate: SheetofReviewerDesignerDepartmentProject
Page TitleBU9<Doc> AC Thursday, August 24, 2023<Designer><Reviewer> 12 32<Title><Page Title>SizeDoc NumberRevDate: SheetofReviewerDesignerDepartmentProject
Page TitleBU9<Doc> AC Thursday, August 24, 2023<Designer><Reviewer> 12 32<Title><Page Title>SizeDoc NumberRevDate: SheetofReviewerDesignerDepartmentProject
Page TitleBU9<Doc> AC Thursday, August 24, 2023<Designer><Reviewer> 12 32<Title><Page Title>
U8PCA9555VDD24VSS12INT1SDA23SCL22P004P015P026P037P048P059P0610P0711P1013P1114P1215P1316P1417P1518P1619P1720A021A12A23R551KR0402-02011%1/16WNIC80.1UF10%16VC0402-0201X7RR981KR0402-02011%1/16WNIR511KR0402-02011%1/16WNI
R59314.7KR0402-02015%1/16WR1341KR0402-02011%1/16WNIR1011KR0402-02011%1/16WR1361KR0402-02011%1/16WNI
R59341KR0402-02011%1/16W
R541KR0402-02011%1/16W
R59371KR0402-02011%1/16WNIR50 331% R0402-02011/16WR5933 331% R0402-02011/16WR484.7KR0402-02015%1/16WR1351KR0402-02011%1/16WR1371KR0402-02011%1/16W
R59351KR0402-02011%1/16WNIR59381KR0402-02011%1/16W
R961KR0402-02011%1/16WHSC1_BOM2R1381KR0402-02011%1/16WNIR531KR0402-02011%1/16W
R59361KR0402-02011%1/16W
R991KR0402-02011%1/16WHSC1_BOM1
R59391KR0402-02011%1/16WNIU39PCA9555VDD24VSS12INT1SDA23SCL22P004P015P026P037P048P059P0610P0711P1013P1114P1215P1316P1417P1518P1619P1720A021A12A23
R561KR0402-02011%1/16WNI
C1020.1UF10%16VC0402-0201X7RR5932 331% R0402-02011/16W
R971KR0402-02011%1/16WNIR521KR0402-02011%1/16WR1331KR0402-02011%1/16WR49 331% R0402-02011/16WR1001KR0402-02011%1/16WPU_U8_PIN1TP_U8_P04TP_U8_P05PCA9555_A0TP_U8_P06PCA9555_A1TP_U8_P07PCA9555_A2SMB_IOEXP_SDASMB_IOEXP_SCLPCA9555_A0PCA9555_A1PCA9555_A2SKU_ID_0SKU_ID_1SKU_ID_2SKU_ID_0SKU_ID_1SKU_ID_2BOARD_ID_0BOARD_ID_1BOARD_ID_2BOARD_ID_2BOARD_ID_1BOARD_ID_0
PU_U39_PIN1PCA9555_2_A0TP_U39_P05PCA9555_2_A1TP_U39_P06PCA9555_2_A2TP_U39_P07TP_U39_P10TP_U39_P11TP_U39_P12TP_U39_P13SMB_IOEXP_2_SDATP_U39_P14TP_U39_P15SMB_IOEXP_2_SCLTP_U39_P16TP_U39_P17PCA9555_2_A0PCA9555_2_A1PCA9555_2_A2



5
5
4
4
3
3
2
2
1
1
D D
C C
B B
A A
FRU
FRU
ADDRESS 0XA2
SMB_PDB_MISC_SDA 7,8,12SMB_PDB_MISC_SCL_R1 7,8P3V3_AUXP3V3_AUXP3V3_AUX
SizeDoc NumberRevDate: SheetofReviewerDesignerDepartmentProject
Page TitleBU9<Doc> AB Thursday, August 24, 2023<Designer><Reviewer> 13 32<Title><Page Title>SizeDoc NumberRevDate: SheetofReviewerDesignerDepartmentProject
Page TitleBU9<Doc> AB Thursday, August 24, 2023<Designer><Reviewer> 13 32<Title><Page Title>SizeDoc NumberRevDate: SheetofReviewerDesignerDepartmentProject
Page TitleBU9<Doc> AB Thursday, August 24, 2023<Designer><Reviewer> 13 32<Title><Page Title>
C90.1UFC0402-020110%16VX7RR614.7KR0402-02015%R66220R0402-02015%NIR604.7KR0402-02015%NIR571K1/16W1%R0402-0201NIU9M24256-BRMN6TPWC_N7E01E12E23SDA5SCL6VCC8VSS4R65220R0402-02015%R64220R0402-02015%R62 331% R0402-02011/16WR594.7KR0402-02015%NIR63 331% R0402-02011/16WR5810K1/16W5%R0402-0201SMB_PDB_MISC_SDASMB_FRU_DATSMB_PDB_MISC_SCL_R1SMB_FRU_CLKFRU_ADDR0FRU_ADDR2FRU_ADDR1FRU_WP_N



5
5
4
4
3
3
2
2
1
1
D D
C C
B B
A A
TO GPU CONN
P52V_HS1P52V_HS1P52V_HS1P52V_HS2P52V_HS2P52V_HS1P52V_HS2P52V_HS2
SizeDoc NumberRevDate: SheetofReviewerDesignerDepartmentProject
Page TitleBU9<Doc> AB Thursday, August 24, 2023<Designer><Reviewer> 14 32<Title><Page Title>SizeDoc NumberRevDate: SheetofReviewerDesignerDepartmentProject
Page TitleBU9<Doc> AB Thursday, August 24, 2023<Designer><Reviewer> 14 32<Title><Page Title>SizeDoc NumberRevDate: SheetofReviewerDesignerDepartmentProject
Page TitleBU9<Doc> AB Thursday, August 24, 2023<Designer><Reviewer> 14 32<Title><Page Title>
J3CONN24_10134701-5544P00LFB1B1B2B2B3B3B4B4B5B5B6B6A1A1A2A2A3A3A4A4A5A5A6A6D1D1D2D2D3D3D4D4D5D5D6D6C1C1C2C2C3C3C4C4C5C5C6C6JP2CONN36_10141042-200A003LFP1_1P1_1P1_2P1_2P1_3P1_3P1_4P1_4P1_5P1_5P1_6P1_6P1_7P1_7P1_8P1_8P1_9P1_9P1_10P1_10P1_11P1_11P1_12P1_12P1_13P1_13P1_14P1_14P1_15P1_15P1_16P1_16P1_17P1_17P1_18P1_18P2_1P2_1P2_2P2_2P2_3P2_3P2_4P2_4P2_5P2_5P2_6P2_6P2_7P2_7P2_8P2_8P2_9P2_9P2_10P2_10P2_11P2_11P2_12P2_12P2_13P2_13P2_14P2_14P2_15P2_15P2_16P2_16P2_17P2_17P2_18P2_18J4CONN36_10146092-555444PLFA1A1A2A2A3A3A4A4A5A5A6A6F1F1F2F2F3F3F4F4F5F5F6F6B1B1B2B2B3B3B4B4B5B5B6B6E1E1E2E2E3E3E4E4E5E5E6E6C1C1C2C2C3C3C4C4C5C5C6C6D1D1D2D2D3D3D4D4D5D5D6D6J1CONN24_10134701-5544P00LFB1B1B2B2B3B3B4B4B5B5B6B6A1A1A2A2A3A3A4A4A5A5A6A6D1D1D2D2D3D3D4D4D5D5D6D6C1C1C2C2C3C3C4C4C5C5C6C6JP1CONN36_10141042-200A003LFP1_1P1_1P1_2P1_2P1_3P1_3P1_4P1_4P1_5P1_5P1_6P1_6P1_7P1_7P1_8P1_8P1_9P1_9P1_10P1_10P1_11P1_11P1_12P1_12P1_13P1_13P1_14P1_14P1_15P1_15P1_16P1_16P1_17P1_17P1_18P1_18P2_1P2_1P2_2P2_2P2_3P2_3P2_4P2_4P2_5P2_5P2_6P2_6P2_7P2_7P2_8P2_8P2_9P2_9P2_10P2_10P2_11P2_11P2_12P2_12P2_13P2_13P2_14P2_14P2_15P2_15P2_16P2_16P2_17P2_17P2_18P2_18J2CONN36_10146092-555444PLFA1A1A2A2A3A3A4A4A5A5A6A6F1F1F2F2F3F3F4F4F5F5F6F6B1B1B2B2B3B3B4B4B5B5B6B6E1E1E2E2E3E3E4E4E5E5E6E6C1C1C2C2C3C3C4C4C5C5C6C6D1D1D2D2D3D3D4D4D5D5D6D6



5
5
4
4
3
3
2
2
1
1
D D
C C
B B
A A
TO VPDB CONNECTOR
SMB_PDB_SCL7SMB_PDB_SDA7SMB_P52V_SCL7SMB_P52V_SDA7 FAN_PWR_EN_BUF 17,26RST_SMB_PDB_BUF_N 8,17PWRGD_P3V3_AUX_MB_BUF 7,24GPU_HSC_EN 24P12V_HPDB_PWRGD 25
PWRGD_P52V_HS1_4287_PG_N20PWRGD_P52V_HS2_4287_PG_N22PWRGD_P52V_HS1_PG12,21PWRGD_P52V_HS2_PG12,23P3V3_HPDB_PG25,26P52V_FANP12V_HPDB
P52V_HS1P52V_HS2P3V3_AUXP3V3_AUXP3V3_AUXP52V_FAN
SizeDoc NumberRevDate: SheetofReviewerDesignerDepartmentProject
Page TitleBU9<Doc> AC Thursday, August 24, 2023<Designer><Reviewer> 15 32<Title><Page Title>SizeDoc NumberRevDate: SheetofReviewerDesignerDepartmentProject
Page TitleBU9<Doc> AC Thursday, August 24, 2023<Designer><Reviewer> 15 32<Title><Page Title>SizeDoc NumberRevDate: SheetofReviewerDesignerDepartmentProject
Page TitleBU9<Doc> AC Thursday, August 24, 2023<Designer><Reviewer> 15 32<Title><Page Title>R16112K<Part Number>1%1/16WR0402-0201HSC1_BOM1R419 0R0402-02015%1/16WHSC1_BOM1
R85 0R0402-02015% 1/16W
D
G
S
U37DMN53D0L-7<Part Number>DGSJ11CONN32_10167141-001LFS2S2S3S3S1S1S7S7S8S8S4S4S5S5S6S6P4P4P3P3P2P2P1P1P5P5P6P6P7P7P8P8P9P9P10P10P11P11P12P12P13P13P14P14P15P15P16P16S9S9S10S10S11S11S12S12S13S13S14S14S15S15S16S16R5899100KR0402-02015%1/16WNIR423 0R0402-02015%1/16WHSC1_BOM1
D
G
S
U30DMN53D0L-7<Part Number>HSC1_BOM1DGSJ15CONN1_10037910-101LFSCR_G1SCR_G1G1G1U3374LVC1G08W5-7A1B2GND3Y4VCC5J16CONN1_10037910-101LFSCR_G1SCR_G1G1G1R420 0R0402-02015%1/16WHSC1_BOM1
R86 0R0402-02015% 1/16WR59144.7KR0402-02015%1/16W<Part Number>R162174K<Part Number>1%1/8WR0805_H26HSC1_BOM1R5898 0R0402-02015%1/16WR5915 0R0402-02015%1/16WR84 0R0402-02015% 1/16WR59134.7KR0402-02015%1/16W<Part Number>R160174K<Part Number>1%1/8WR0805_H26HSC1_BOM1
D
G
S
U36DMN53D0L-7<Part Number>DGS
D
G
S
U29DMN53D0L-7<Part Number>HSC1_BOM1DGS R16312K<Part Number>1%1/16WR0402-0201HSC1_BOM1
R87 0R0402-02015% 1/16W
R424 0R0402-02015%1/16WHSC1_BOM1C890.1UF10%16VC0402-0201X7RSMB_PDB_R_SCLSMB_PDB_R_SDASMB_P52V_R_SCLSMB_P52V_R_SDAPWRGD_P52V_HS_PG
PWRGD_P52V_HS1_4287_PG_R_NPWRGD_P52V_HS1_4287_PGPWRGD_P52V_HS2_4287_PGPWRGD_P52V_HS2_4287_PG_R_NPWRGD_P52V_HS1_PGPWRGD_P52V_HS2_PGPWRGD_P52V_HS_PG_R2PWRGD_P52V_HS_PGPWRGD_P3V3_HPDBPWRGD_P3V3_HPDB_R_NPWRGD_P3V3_HPDB_RPWRGD_P3V3_HPDB



5
5
4
4
3
3
2
2
1
1
D D
C C
B B
A A
48V POWER CONNECTOR
P52V_1_BUSBAR27P52V_2_BUSBAR28
P52V_1P52V_1P52V_2P52V_2SizeDoc NumberRevDate: SheetofReviewerDesignerDepartmentProject
Page TitleBU9<Doc> AB Thursday, August 24, 2023<Designer><Reviewer> 16 32<Title><Page Title>SizeDoc NumberRevDate: SheetofReviewerDesignerDepartmentProject
Page TitleBU9<Doc> AB Thursday, August 24, 2023<Designer><Reviewer> 16 32<Title><Page Title>SizeDoc NumberRevDate: SheetofReviewerDesignerDepartmentProject
Page TitleBU9<Doc> AB Thursday, August 24, 2023<Designer><Reviewer> 16 32<Title><Page Title>
J6CONN36_10106267-4001501LFP4_1P4_1P4_2P4_2P4_3P4_3P4_4P4_4P4_5P4_5P4_6P4_6P4_7P4_7P4_8P4_8P2_1P2_1P2_2P2_2P2_3P2_3P2_4P2_4P2_5P2_5P2_6P2_6P2_7P2_7P2_8P2_8P1_1P1_1P1_2P1_2P1_3P1_3P1_4P1_4P1_5P1_5P1_6P1_6P1_7P1_7P1_8P1_8P3_1P3_1P3_2P3_2P3_3P3_3P3_4P3_4P3_5P3_5P3_6P3_6P3_7P3_7P3_8P3_8A1A1B1B1C1C1D1D1J7CONN36_10106267-4001501LFP4_1P4_1P4_2P4_2P4_3P4_3P4_4P4_4P4_5P4_5P4_6P4_6P4_7P4_7P4_8P4_8P2_1P2_1P2_2P2_2P2_3P2_3P2_4P2_4P2_5P2_5P2_6P2_6P2_7P2_7P2_8P2_8P1_1P1_1P1_2P1_2P1_3P1_3P1_4P1_4P1_5P1_5P1_6P1_6P1_7P1_7P1_8P1_8P3_1P3_1P3_2P3_2P3_3P3_3P3_4P3_4P3_5P3_5P3_6P3_6P3_7P3_7P3_8P3_8A1A1B1B1C1C1D1D1GND_1_BUSBARGND_2_BUSBARNC_J6_C1NC_J6_D1NC_J7_C1NC_J7_D1



5
5
4
4
3
3
2
2
1
1
D D
C C
B B
A A
TO FAN_BP CONNECTOR
SMB_PDB_FAN_0_SCL8SMB_PDB_FAN_0_SDA8 FAN_PWR_EN_BUF 15,17,26RST_SMB_PDB_BUF_N 8,15,17SMB_PDB_FAN_1_SCL8 FAN_PWR_EN_BUF 15,17,26SMB_PDB_FAN_1_SDA8 RST_SMB_PDB_BUF_N 8,15,17PRSNT_FAN_BP0_N12PRSNT_FAN_BP1_N12P52V_FANP3V3_AUXP3V3_AUXP52V_FANP12V_FAN_LEDP12V_FAN_LEDP3V3_AUXP3V3_AUX
SizeDoc NumberRevDate: SheetofReviewerDesignerDepartmentProject
Page TitleBU9<Doc> AC Thursday, August 24, 2023<Designer><Reviewer> 17 32<Title><Page Title>SizeDoc NumberRevDate: SheetofReviewerDesignerDepartmentProject
Page TitleBU9<Doc> AC Thursday, August 24, 2023<Designer><Reviewer> 17 32<Title><Page Title>SizeDoc NumberRevDate: SheetofReviewerDesignerDepartmentProject
Page TitleBU9<Doc> AC Thursday, August 24, 2023<Designer><Reviewer> 17 32<Title><Page Title>
R592705%R0402-0201 1/16WR7105%R0402-0201 1/16WR7805%R0402-0201 1/16WR7505%R0402-0201 1/16WR7405%R0402-0201 1/16WR591210KR0402-02015%1/16WR592805%R0402-0201 1/16WR7305%R0402-0201 1/16WR7605%R0402-0201 1/16WJ8CONN12_10121505-0004082LFS2S2S3S3S1S1S7S7S8S8S4S4S5S5S6S6P4P4P3P3P2P2P1P1R591110KR0402-02015%1/16WR7705%R0402-0201 1/16WR7205%R0402-0201 1/16WJ9CONN12_10121505-0004082LFS2S2S3S3S1S1S7S7S8S8S4S4S5S5S6S6P4P4P3P3P2P2P1P1SMB_PDB_FAN_0_R_SCLSMB_PDB_FAN_0_R_SDAFAN_PWR_EN_0_RRST_SMB_FAN_0_R_NPRSNT_FAN_BP0_R_NSMB_PDB_FAN_1_R_SCLFAN_PWR_EN_1_RSMB_PDB_FAN_1_R_SDARST_SMB_FAN_1_R_NPRSNT_FAN_BP1_R_N



5
5
4
4
3
3
2
2
1
1
D D
C C
B B
A A
ECAP_P48V_1
P52V_HS1_EN20,21,27P52V_HS1P52V_HS1P52V_HS1
SizeDoc NumberRevDate: SheetofReviewerDesignerDepartmentProject
Page TitleBU9<Doc> AB Thursday, August 24, 2023<Designer><Reviewer> 18 32<Title><Page Title>SizeDoc NumberRevDate: SheetofReviewerDesignerDepartmentProject
Page TitleBU9<Doc> AB Thursday, August 24, 2023<Designer><Reviewer> 18 32<Title><Page Title>SizeDoc NumberRevDate: SheetofReviewerDesignerDepartmentProject
Page TitleBU9<Doc> AB Thursday, August 24, 2023<Designer><Reviewer> 18 32<Title><Page Title>
D
G
SPU32N7002KW<Part Number>DGS+PC321000UF<Part Number>20%80V12+PC401000UF<Part Number>20%80V  12 PQ15PSMN3R7-100BSE  <Part Number>DGSPQ17METR3904-G<Part Number>BEC+PC281000UF<Part Number>20%80V12 PR1020R0402-02015%<Part Number>PR9820K<Part Number>R1206XN1/4W1%PR10012W1%R2512XU_H30<Part Number>+PC331000UF<Part Number>20%80V12+PC411000UF<Part Number>20%80V  12+PC291000UF<Part Number>20%80V12+PC421000UF<Part Number>20%80V  12+PC301000UF<Part Number>20%80V12 PR10112W1%R2512XU_H30<Part Number>PR990R0402-02015%<Part Number>+PC431000UF<Part Number>20%80V  12+PC311000UF<Part Number>20%80V12P52V_HS1_EN_DISCHARGEP52V_HS1_EN_DISCHARGE_VBEP52V_HS1_EN_DISCHARGE_VBE_RP52V_HS1_EN_DISCHARGE_N



5
5
4
4
3
3
2
2
1
1
D D
C C
B B
A A
ECAP_P48V_2
P52V_HS2_EN22,23,28P52V_HS2P52V_HS2P52V_HS2
SizeDoc NumberRevDate: SheetofReviewerDesignerDepartmentProject
Page TitleBU9<Doc> AB Thursday, August 24, 2023<Designer><Reviewer> 19 32<Title><Page Title>SizeDoc NumberRevDate: SheetofReviewerDesignerDepartmentProject
Page TitleBU9<Doc> AB Thursday, August 24, 2023<Designer><Reviewer> 19 32<Title><Page Title>SizeDoc NumberRevDate: SheetofReviewerDesignerDepartmentProject
Page TitleBU9<Doc> AB Thursday, August 24, 2023<Designer><Reviewer> 19 32<Title><Page Title>PR10612W1%R2512XU_H30<Part Number>PR10420K1/4W1%R1206XN+PC351000UF<Part Number>20%80V12 PR1050R0402-02015%<Part Number>D
G
S
PU42N7002KW<Part Number>DGS+PC441000UF<Part Number>20%80V  12 PR10712W1%R2512XU_H30<Part Number>+PC361000UF<Part Number>20%80V12 PQ16PSMN3R7-100BSE  <Part Number>DGSPR1030R0402-02015%<Part Number>+PC451000UF<Part Number>20%80V  12+PC371000UF<Part Number>20%80V12+PC461000UF<Part Number>20%80V  12+PC381000UF<Part Number>20%80V12+PC341000UF<Part Number>20%80V12+PC471000UF<Part Number>20%80V  12+PC391000UF<Part Number>20%80V12 PQ18METR3904-G<Part Number>BECP52V_HS2_EN_DISCHARGE_NP52V_HS2_EN_DISCHARGE_VBEP52V_HS2_EN_DISCHARGE_VBE_RP52V_HS2_EN_DISCHARGE



5
5
4
4
3
3
2
2
1
1
D D
C C
B B
A A
60.25155.557
typical
38.487
HOT SWAP P52V_HS
53.675
41.22
57.756
min.
Falling PG
38.184
40.209
45.62
36.815
 UV/OV/PG Thresholds
Falling UVLO
42.25
39.68
Falling OVLO
40.726
Unit: V
59.676
Rising UVLO
37.736
Rising OVLO
36.269
max.
43.91
Rising PG
56.719
Current limit threshold :16mV
52V HOT SWAP_LTC4287
HSC OCP=  160AImax: 67A in 1sec     106A in 400us
SMB Address:0x40(7bit),0x80(8bit)              ADR0=0ADR1=0
P52V_HS1_ADR0 20,21P52V_HS1_ADR1 20,21
P52V_HS1_4287_GATE_R 27P52V_HS_4287_S1P 27P52V_HS1_4287_GATE2_R 27P52V_HS_4287_S1N 27P52V_HS_4287_ADC_P 27P52V_HS_4287_ADC_N 27P52V_HS_4287_S2P 27P52V_HS_4287_S2N 27P52V_HS1_OV21,27P52V_HS1_UVLO_EN21,27P52V_HS1_EN18,21,27PWRGD_P52V_HS1_4287_PG_N 15P52V_HS1_FLT 12,21P52V_HS1_TEMP 27P52V_HS1_ADR020,21P52V_HS1_ADR120,21SMB_P52V_PDB_SCL7,21,22,23,27SMB_P52V_PDB_SDA7,21,22,23,27P52V_HS1_INTVCCGND_FIELD_SIGNALP52V_HS1_DVCCP52V_HS1_DVCC
P52V_1P52V_HS1P52V_HS1P52V_HS1_INTVCCP52V_HS1P52V_HS1_INTVCCP52V_HS1_INTVCC
SizeDoc NumberRevDate: SheetofReviewerDesignerDepartmentProject
Page TitleBU9<Doc> AC Thursday, August 24, 2023<Designer><Reviewer> 20 32<Title><Page Title>SizeDoc NumberRevDate: SheetofReviewerDesignerDepartmentProject
Page TitleBU9<Doc> AC Thursday, August 24, 2023<Designer><Reviewer> 20 32<Title><Page Title>SizeDoc NumberRevDate: SheetofReviewerDesignerDepartmentProject
Page TitleBU9<Doc> AC Thursday, August 24, 2023<Designer><Reviewer> 20 32<Title><Page Title>R1570<Part Number>R0402-02015%NI
PC50.1UF25V10%C0402-0201X7R<Part Number>HSC1_BOM1PC48747UF6.3V20%C1206_H76X6S<Part Number>NI
PC31UF100V10%C1206_H66X7R<Part Number>HSC1_BOM1PC5810.033UFC060310%100V<Part Number>X7RHSC1_BOM1PC830.68UF16V10%C0603X7R<Part Number>NILTC4287AUK#TRPBFPU1HSC1_BOM11SOURCE2GATE23GATE1ADC-4SENSE1-5SENSE1+6ADC+7SENSE2-8SENSE2+9VDD10UV11OV12INTVCC13GND14DVCC15ADR016ADR117NC118MODE19TMR20CLKIN21CLKOUT22EN||EN#23SIO24SCK2526CS#SCL27SDAI28SDAO29GPIO830GPIO731GPIO632GPIO533GPIO434GPIO335GPIO236GPIO137FB38VDSFB3940TH_GNDPR2412K<Part Number>1%1/16WR0402-0201HSC1_BOM1PC584 0.22UFNIPR220 100NI5% R0603_H24<Part Number>PR21310KNIR0402-02011%1/16W<Part Number>PC5510.056UF16V10% C0402-0201X7R<Part Number>NIPC80.1UF100VC0603X7R<Part Number>10%HSC1_BOM1PR21410KHSC1_BOM1R0402-02011%1/16W <Part Number>PJ1SHORTHSC1_BOM11122PC61000PF5%50VC0402-0201<Part Number>X7RHSC1_BOM1U31M95256-RDW6TPNIS#1Q2W#3VSS4D5C6HOLD#7VCC8 PR6999 100NI<Part Number>5% R0603_H24PR2111M<Part Number>1%1/16WR0402-0201NIR5855 0R0402-02015%HSC1_BOM1PC820.033UFC060310%100V<Part Number>X7RHSC1_BOM1PC5830.1UF100VC0603X7R<Part Number>10%HSC1_BOM1PC585 0.22UFNIPR110HSC1_BOM1PR25499K<Part Number>1%1/8WR0805_H26HSC1_BOM1PD151N4448WS-7-FSOD323<Part Number>HSC1_BOM112PR210 01/16W 5%R0402-0201<Part Number>NIPR2090HSC1_BOM1PC41UF16V10%C0402-0201X6S <Part Number>HSC1_BOM1PR699833K<Part Number>1%1/16WR0402HSC1_BOM1
R1580<Part Number>R0402-02015%HSC1_BOM1R1560<Part Number>R0402-02015%NIR5856 0R0402-02015%HSC1_BOM1R5869 0R0402-02015%HSC1_BOM1PR2730.1KR0402-02011%1/16W<Part Number>HSC1_BOM1PR2633K<Part Number>1%1/16WR0402HSC1_BOM1PR3301/16W5%R0402-0201<Part Number>NIPR21210KR0402-02011%1/16W<Part Number>HSC1_BOM1PR2875KR0402-02011%1/16W<Part Number>HSC1_BOM1PD161N4448WS-7-FSOD323<Part Number>HSC1_BOM112PR23174K<Part Number>1%1/8WR0805HSC1_BOM1PC72200PF50V10%C0402-0201X7R<Part Number>HSC1_BOM1R1590<Part Number>R0402-02015%HSC1_BOM1P52V_HS1_ADR0P52V_HS1_ADR1P52V_HS1_CSP52V_HS1_SIOP52V_HS1_DVCCP52V_HS1_SCKP52V_HS1_SIOP52V_HS1_GATE_RCP52V_HS1_4287_GATE2_RCP52V_HS1_DVCCP52V_HS1_OVP52V_HS1_4287_GATE_RP52V_HS1_4287_GATE2_RP52V_HS1_UVLO_ENP52V_HS1_TEMPSMB_P52V_PDB_SCL_R3SMB_P52V_HS1_SDAISMB_P52V_HS1_SDAOP52V_HS1_VDSFBP52V_HS1_SIOP52V_HS1_CSP52V_HS1_FBP52V_HS1_MODEP52V_HS1_TMRHS1_TMR1HS1_TMR2P52V_HS1_CLKINP52V_HS1_SCK
P52V_HS1_GATE_R1P52V_HS1_GATE2_R1



5
5
4
4
3
3
2
2
1
1
D D
C C
B B
A A
SMB Address:0x1C(7bit),0x38(8bit)              ADR0=0ADR1=1
pop PR6938 when use ADM1272
52V HOT SWAP_ADM1272
HSC OCP= 51V / 144A (7360W)Imax: 67A in 1sec     106A in 400us
38.360 39.710
56.54
typical
39.04
60.06
Rising UVLO 43.168
42.63
41.060
58.27
Rising PG
Falling PG
Falling OVLO
min.
44.443
40.82
57.02
Falling UVLO
58.75
44.49
41.893
 UV/OV/PG Thresholds
Rising OVLO
40.21 41.42
60.54
max.
Unit: V
R148/R149 should be installed for both 1272/4287
PC11 need change to CH4473K1902(CAP CHIP 0.47U 16V (+-10%,X7R,0603))
P52V_HS1_ADR0 20,21P52V_HS1_ADR1 20,21
P52V_HS1_OV20,27P52V_HS1_UVLO_EN20,27P52V_HS1_1272_GATE27P52V_HS_1272_S_P27P52V_HS_1272_S_N27P52V_HS1_TEMPP 27P52V_HS1_TEMPN 27P52V_HS1_EN18,20,27PWRGD_P52V_HS1_PG 12,15P52V_HS1_ADR020,21P52V_HS1_ADR120,21SMB_P52V_PDB_SCL_R121SMB_P52V_PDB_SDA7,20,22,23,27SMB_P52V_PDB_SCL7,20,22,23,27SMB_P52V_PDB_SCL_R1 21P52V_HS1_FLT 12,20P3V3_AUXP52V_HS1_VCAPGND_FIELD_SIGNAL
P52V_1GND_FIELD_SIGNALGND_FIELD_SIGNALP52V_HS1P52V_1P52V_HS1P52V_HS1_VCCP52V_HS1GND_FIELD_SIGNALGND_FIELD_SIGNALP52V_HS1_VCAPGND_FIELD_SIGNALGND_FIELD_SIGNALP3V3_AUXP52V_HS1_VCCGND_FIELD_SIGNALGND_FIELD_SIGNALGND_FIELD_SIGNALP3V3_AUXSizeDoc NumberRevDate: SheetofReviewerDesignerDepartmentProject
Page TitleBU9<Doc> AC Thursday, August 24, 2023<Designer><Reviewer> 21 32<Title><Page Title>SizeDoc NumberRevDate: SheetofReviewerDesignerDepartmentProject
Page TitleBU9<Doc> AC Thursday, August 24, 2023<Designer><Reviewer> 21 32<Title><Page Title>SizeDoc NumberRevDate: SheetofReviewerDesignerDepartmentProject
Page TitleBU9<Doc> AC Thursday, August 24, 2023<Designer><Reviewer> 21 32<Title><Page Title>
R1474.7K<Part Number>R0402-02015%NIPC110.1UF100VC0603X7R<Part Number>10%HSC1_BOM2PR3220KR0805_H261%<Part Number>HSC1_BOM2PR6934100KR0402-02011%HSC1_BOM2<Part Number>PR693571.5KR0402-02011%<Part Number>NIR3720<Part Number>R0402-02015%HSC1_BOM2PC90.1UFC0402-020125VX7R<Part Number>HSC1_BOM2PR69312.26K<Part Number>R0402-02011%HSC1_BOM2R145 0R0402-02015%HSC1_BOM2R1504.7K<Part Number>R0402-02015%HSC1_BOM2R3730<Part Number>R0402-02015%HSC1_BOM2R14911.5K<Part Number>R0402-02011%PR495.3K<Part Number>R0805_H261%HSC1_BOM2PR203.83KR0402-0201  <Part Number>1%PU7ADM1272-1ACPZ-RLHSC1_BOM2VOUT31GATE32SENSE-38VCC41DNC226UVH45UVL46GND19SDAI10SDAO11SCL9RND48TEMP+44MCB12ADR18ADR07VREG42ISTART2PWRGIN18DVDT30VCAP3DNC125PWRGD17NC524OV47ISET1DNC327DNC428DNC533DNC634DNC735DNC836DNC937DNC1040NC423NC322NC221NC120TEMP-43EFAULT5ESTART4ENABLE6GPO114GPO213VCP29FAULT#15RESTART#16SENSE+39EPGNDPAD1EPVCCPAD2PR2153.6K1%R0402-0201<Part Number>  PC122200PF50VC0402-0201X7R<Part Number>  PC101UF<Part Number>C0402-020125VX6SHSC1_BOM2PC5860.1UFC0402-0201<Part Number>25VX7RHSC1_BOM2PR182.05M<Part Number>1%R0805_H26NIPR36330KR0402-02011%<Part Number>NIR3740<Part Number>R0402-02015%NIR3574.7K<Part Number>R0402-02015%NIR1510R0402-02015%<Part Number>HSC1_BOM2
PR51005%<Part Number>R1206XNHSC1_BOM2
R3580R0402-02015%<Part Number>NIPC589 1000PFC0402-020150VNI<Part Number>X7RPC130.15UF<Part Number>C0805_H57100VX7RHSC1_BOM2PR69322.43K<Part Number>1%R0402-0201HSC1_BOM2PC5911UFC060325VX7R<Part Number>HSC1_BOM2PR9310K1%R0402-0201<Part Number>HSC1_BOM2PC5870.1UFC1206_H42100VX7R<Part Number>HSC1_BOM2R148174K1%R0805_H26<Part Number>R81 05%R0402-0201 1/16WHSC1_BOM2PR192.05MR0805_H261%HSC1_BOM2<Part Number>PR37390K1%R0402-0201<Part Number>HSC1_BOM2R1464.7K<Part Number>R0402-02015%NI PR35100KR0402-02011%HSC1_BOM2R144 0R0402-02015%HSC1_BOM2PR3116.9K1%R0402-0201<Part Number>HSC1_BOM2PC5900.01UFC0402-020150V<Part Number>X7RHSC1_BOM2PR693397.6K<Part Number>R0402-02011%  R3710<Part Number>R0402-02015%NI
PR1795.3K1%R0805_H26<Part Number>HSC1_BOM2PC5881UFC1206_H66<Part Number>100VX7RHSC1_BOM2P52V_HS1_GPO1P52V_HS1_FLTP52V_HS1_ADR0P52V_HS1_ADR1
P52V_HS1_UVHP52V_HS1_VCCP52V_HS1_PWRGINP52V_HS1_ISETP52V_HS1_ISTARTP52V_HS1_VCPP52V_HS1_TEMPPP52V_HS1_TEMPNP52V_HS1_VCAPP52V_HS1_ENP52V_HS1_MCBP52V_HS1_ADR0P52V_HS1_GPO1P52V_HS1_ADR1P52V_HS1_GPO2SMB_CM_HS1_3V3SB_DATISMB_CM_HS1_3V3SB_DATOP52V_HS1_VREGP52V_HS1_RND
P52V_HS1_DV_DT_R
P52V_HS1_EFAULT_R
P52V_HS1_ESTART_R
P52V_HS1_DV_DTP52V_HS1_ESTARTP52V_HS1_EFAULTP52V_HS1_GPO2P52V_HS1_FLT



5
5
4
4
3
3
2
2
1
1
D D
C C
B B
A A
Current limit threshold :16mV
52V HOT SWAP_LTC4287
min.
37.736
53.675 59.676
38.487
40.726
55.557
42.25
 UV/OV/PG Thresholds
45.62
Rising PG 38.184
36.269
57.756
typical
Falling OVLO
60.251
Falling UVLO
36.815 40.209
43.91
Falling PG
Rising OVLO
41.22
Rising UVLO
HOT SWAP P52V_HS
Unit: V
39.68
56.719
max.
SMB Address:0x41(7bit),0x82(8bit)              ADR0=NCADR1=0
HSC OCP=  160AImax: 67A in 1sec     106A in 400us
P52V_HS2_4287_GATE_R 28P52V_HS2_4287_S1P 28P52V_HS2_4287_GATE2_R 28P52V_HS2_4287_S1N 28P52V_HS2_4287_ADC_P 28P52V_HS2_4287_ADC_N 28P52V_HS2_4287_S2P 28P52V_HS2_4287_S2N 28P52V_HS2_OV23,28P52V_HS2_UVLO_EN23,28P52V_HS2_EN19,23,28PWRGD_P52V_HS2_4287_PG_N 15P52V_HS2_FLT 12,23P52V_HS2_TEMP 28P52V_HS2_ADR022,23P52V_HS2_ADR122,23SMB_P52V_PDB_SCL7,20,21,23,27SMB_P52V_PDB_SDA7,20,21,23,27P52V_HS2_ADR0 22,23P52V_HS2_ADR1 22,23
P52V_2P52V_HS2P52V_HS2P52V_HS2_INTVCCP52V_HS2P52V_HS2_INTVCCP52V_HS2_INTVCCP52V_HS2_DVCCP52V_HS2_DVCCP52V_HS2_INTVCCGND1_FIELD_SIGNALSizeDoc NumberRevDate: SheetofReviewerDesignerDepartmentProject
Page TitleBU9<Doc> AC Thursday, August 24, 2023<Designer><Reviewer> 22 32<Title><Page Title>SizeDoc NumberRevDate: SheetofReviewerDesignerDepartmentProject
Page TitleBU9<Doc> AC Thursday, August 24, 2023<Designer><Reviewer> 22 32<Title><Page Title>SizeDoc NumberRevDate: SheetofReviewerDesignerDepartmentProject
Page TitleBU9<Doc> AC Thursday, August 24, 2023<Designer><Reviewer> 22 32<Title><Page Title>
PR7005174K<Part Number>1%1/8WR0805HSC1_BOM1R58760<Part Number>R0402-02015%HSC1_BOM1
PC5970.033UFC060310%100V<Part Number>X7RHSC1_BOM1R58740<Part Number>R0402-02015%NI
PC6000.1UF25V10%C0402-0201X7R<Part Number>HSC1_BOM1R5872 0R0402-02015%HSC1_BOM1PC60547UF6.3V20%C1206_H76X6S<Part Number>NI
PR7002 100NI<Part Number>R0603_H24PD171N4448WS-7-FSOD323<Part Number>HSC1_BOM112PC5930.1UF100VC0603X7R<Part Number>10%HSC1_BOM1PR701430.1KR0402-02011%1/16W<Part Number>HSC1_BOM1PR700901/16W5%R0402-0201<Part Number>NIPR700610KR0402-02011%1/16W<Part Number>HSC1_BOM1PR701575KR0402-02011%1/16W<Part Number>HSC1_BOM1PC6032200PF50V10%C0402-0201X7R<Part Number>HSC1_BOM1PC596 0.22UFNIPC5940.033UFC060310%100V<Part Number>X7RHSC1_BOM1R5870 0R0402-02015%HSC1_BOM1U32M95256-RDW6TPNIS#1Q2W#3VSS4D5C6HOLD#7VCC8PC6011000PF5%50VC0402-0201<Part Number>X7RHSC1_BOM1PR7003 100NI<Part Number>R0603_H24PR701012K<Part Number>1%1/16WR0402-0201HSC1_BOM1PC6020.68UF16V10%C0603X7R<Part Number>NIPD181N4448WS-7-FSOD323<Part Number>HSC1_BOM112PR700710KNIR0402-02011%1/16W<Part Number>PC6040.056UF16V10% C0402-0201X7R<Part Number>NIPR701610KHSC1_BOM1R0402-02011%1/16W <Part Number>PC598 0.22UFNIPJ5SHORTHSC1_BOM11122R5871 0R0402-02015%HSC1_BOM1PR7004499K<Part Number>1%1/8WR0805_H26HSC1_BOM1PC5920.1UF100VC0603X7R<Part Number>10%HSC1_BOM1PR700133K<Part Number>1%1/16WR0402HSC1_BOM1PR70111M<Part Number>1%1/16WR0402-0201NIPR700033K<Part Number>1%1/16WR0402HSC1_BOM1PC5991UF16V10%C0402-0201X6S <Part Number>HSC1_BOM1
R58750<Part Number>R0402-02015%NIR58730<Part Number>R0402-02015%NIPR70130HSC1_BOM1PR7008 01/16W 5%R0402-0201<Part Number>NILTC4287AUK#TRPBFPU8HSC1_BOM11SOURCE2GATE23GATE1ADC-4SENSE1-5SENSE1+6ADC+7SENSE2-8SENSE2+9VDD10UV11OV12INTVCC13GND14DVCC15ADR016ADR117NC118MODE19TMR20CLKIN21CLKOUT22EN||EN#23SIO24SCK2526CS#SCL27SDAI28SDAO29GPIO830GPIO731GPIO632GPIO533GPIO434GPIO335GPIO236GPIO137FB38VDSFB3940TH_GNDPR70120HSC1_BOM1PC5951UF100V10%C1206_H66X7R<Part Number>HSC1_BOM1P52V_HS2_GATE_RCP52V_HS2_4287_GATE2_RCP52V_HS2_DVCCP52V_HS2_OVP52V_HS2_4287_GATE_RP52V_HS2_4287_GATE2_RP52V_HS2_UVLO_ENP52V_HS2_TEMPSMB_P52V_PDB_SCL_R4SMB_P52V_HS2_SDAISMB_P52V_HS2_SDAOP52V_HS2_VDSFBP52V_HS2_SIOP52V_HS2_CSP52V_HS2_FBP52V_HS2_MODEP52V_HS2_TMRHS2_TMR1HS2_TMR2P52V_HS2_CLKINP52V_HS2_SCKP52V_HS2_CSP52V_HS2_SIOP52V_HS2_DVCCP52V_HS2_SCKP52V_HS2_SIOP52V_HS2_ADR0P52V_HS2_ADR1P52V_HS2_GATE_R1P52V_HS2_GATE2_R1



5
5
4
4
3
3
2
2
1
1
D D
C C
B B
A A
SMB Address:0x13(7bit),0x26(8bit)              ADR0=0ADR1=1
52V HOT SWAP_ADM1272
pop PR6938 when use ADM1272
58.75
40.82
Falling OVLO 58.27
43.168
max.
39.04 40.21
39.710
41.893
Falling UVLO
44.443
Falling PG
41.060
Rising UVLO
60.54
typical
Rising OVLO
38.360
44.49
57.02
min.
Rising PG 42.63
Unit: V
60.06
41.42
56.54
 UV/OV/PG Thresholds
R5880/R5881 should be installed for both 1272/4287
HSC OCP= 51V / 144A (7360W)Imax: 67A in 1sec     106A in 400us
PC614 need change to CH4473K1902(CAP CHIP 0.47U 16V (+-10%,X7R,0603))
P52V_HS2_OV22,28P52V_HS2_UVLO_EN22,28P52V_HS2_1272_GATE28P52V_HS2_1272_S_P28P52V_HS2_1272_S_N28P52V_HS2_TEMPP 28P52V_HS2_TEMPN 28P52V_HS2_EN19,22,28PWRGD_P52V_HS2_PG 12,15P52V_HS2_ADR022,23P52V_HS2_ADR122,23SMB_P52V_PDB_SCL_R223SMB_P52V_PDB_SDA7,20,21,22,27SMB_P52V_PDB_SCL7,20,21,22,27SMB_P52V_PDB_SCL_R2 23P52V_HS2_FLT 12,22P52V_HS2_ADR0 22,23P52V_HS2_ADR1 22,23
P52V_2GND1_FIELD_SIGNALGND1_FIELD_SIGNALP52V_HS2P52V_2P52V_HS2P52V_HS2_VCCP52V_HS2GND1_FIELD_SIGNALGND1_FIELD_SIGNALP52V_HS2_VCAPGND1_FIELD_SIGNALGND1_FIELD_SIGNALP3V3_AUXP52V_HS2_VCCGND1_FIELD_SIGNALGND1_FIELD_SIGNALGND1_FIELD_SIGNALP3V3_AUXP3V3_AUXP52V_HS2_VCAPGND1_FIELD_SIGNALSizeDoc NumberRevDate: SheetofReviewerDesignerDepartmentProject
Page TitleBU9<Doc> AC Thursday, August 24, 2023<Designer><Reviewer> 23 32<Title><Page Title>SizeDoc NumberRevDate: SheetofReviewerDesignerDepartmentProject
Page TitleBU9<Doc> AC Thursday, August 24, 2023<Designer><Reviewer> 23 32<Title><Page Title>SizeDoc NumberRevDate: SheetofReviewerDesignerDepartmentProject
Page TitleBU9<Doc> AC Thursday, August 24, 2023<Designer><Reviewer> 23 32<Title><Page Title>
PC6131UF<Part Number>C0402-020125VX6SHSC1_BOM2
PR70201005%<Part Number>R1206XNHSC1_BOM2PR70232.05M<Part Number>1%R0805_H26NIPR7035330KR0402-02011%<Part Number>NIR58880R0402-02015%<Part Number>HSC1_BOM2PC6140.1UF100VC0603X7R<Part Number>10%HSC1_BOM2R58910<Part Number>R0402-02015%HSC1_BOM2
PC6070.1UFC1206_H42100VX7R<Part Number>HSC1_BOM2PC6160.15UF<Part Number>C0805_H57100VX7RHSC1_BOM2PC609 1000PFC0402-020150VNI<Part Number>X7RPR70252.43K<Part Number>1%R0402-0201HSC1_BOM2PC6111UFC060325VX7R<Part Number>HSC1_BOM2PR703110K1%R0402-0201<Part Number>HSC1_BOM2R5880174K1%R0805_H26<Part Number>R5886 05%R0402-0201 1/16WHSC1_BOM2PR70242.05MR0805_H261%HSC1_BOM2<Part Number>PR7036390K1%R0402-0201<Part Number>HSC1_BOM2R58844.7K<Part Number>R0402-02015%NIR58920<Part Number>R0402-02015%NI PR7034100KR0402-02011%HSC1_BOM2R58940<Part Number>R0402-02015%NIR5882 0R0402-02015%HSC1_BOM2PR703216.9K1%R0402-0201<Part Number>HSC1_BOM2PC6100.01UFC0402-020150V<Part Number>X7RHSC1_BOM2PR702697.6K<Part Number>R0402-02011%  PC6081UFC1206_H66<Part Number>100VX7RHSC1_BOM2R58854.7K<Part Number>R0402-02015%NIR58950<Part Number>R0402-02015%HSC1_BOM2
PR70212.26K<Part Number>R0402-02011%HSC1_BOM2PR703320KR0805_H261%<Part Number>HSC1_BOM2PR7027100KR0402-02011%HSC1_BOM2<Part Number>PR702971.5KR0402-02011%<Part Number>NIPC6120.1UFC0402-020125VX7R<Part Number>HSC1_BOM2R58894.7K<Part Number>R0402-02015%NI
PR701995.3K<Part Number>R0805_H261%HSC1_BOM2R5883 0R0402-02015%HSC1_BOM2R58900R0402-02015%<Part Number>NI
PR702295.3K1%R0805_H26<Part Number>HSC1_BOM2R58874.7K<Part Number>R0402-02015%HSC1_BOM2R588111.5K<Part Number>R0402-02011%PC6060.1UFC0402-0201<Part Number>25VX7RHSC1_BOM2PR70283.83KR0402-0201  <Part Number>1%PU9ADM1272-1ACPZ-RLHSC1_BOM2VOUT31GATE32SENSE-38VCC41DNC226UVH45UVL46GND19SDAI10SDAO11SCL9RND48TEMP+44MCB12ADR18ADR07VREG42ISTART2PWRGIN18DVDT30VCAP3DNC125PWRGD17NC524OV47ISET1DNC327DNC428DNC533DNC634DNC735DNC836DNC937DNC1040NC423NC322NC221NC120TEMP-43EFAULT5ESTART4ENABLE6GPO114GPO213VCP29FAULT#15RESTART#16SENSE+39EPGNDPAD1EPVCCPAD2PR703053.6K1%R0402-0201<Part Number>  PC6152200PF50VC0402-0201X7R<Part Number>  P52V_HS2_UVHP52V_HS2_VCCP52V_HS2_PWRGINP52V_HS2_ISETP52V_HS2_ISTARTP52V_HS2_VCPP52V_HS2_TEMPPP52V_HS2_TEMPNP52V_HS2_VCAPP52V_HS2_ENP52V_HS2_MCBP52V_HS2_ADR0P52V_HS2_GPO1P52V_HS2_ADR1P52V_HS2_GPO2SMB_CM_HS2_3V3SB_DATISMB_CM_HS2_3V3SB_DATOP52V_HS2_VREGP52V_HS2_RND
P52V_HS2_DV_DT_R
P52V_HS2_EFAULT_R
P52V_HS2_ESTART_R
P52V_HS2_DV_DTP52V_HS2_ESTARTP52V_HS2_EFAULTP52V_HS2_GPO2P52V_HS2_FLTP52V_HS2_GPO1P52V_HS2_FLTP52V_HS2_ADR0P52V_HS2_ADR1



5
5
4
4
3
3
2
2
1
1
D D
C C
B B
A A
GPU HSC EN
GPU HSC EN BUFFER
GPU_HSC_EN15 GPU_HSC1_BUF_EN 27GPU_HSC2_BUF_EN 28
PWRGD_P3V3_AUX_MB_BUF7,15P3V3_AUXP3V3_AUXP52V_1_FUSE_1P52V_2_FUSE_1
P3V3_AUX
SizeDoc NumberRevDate: SheetofReviewerDesignerDepartmentProject
Page TitleBU9<Doc> AB Thursday, August 24, 2023<Designer><Reviewer> 24 32<Title><Page Title>SizeDoc NumberRevDate: SheetofReviewerDesignerDepartmentProject
Page TitleBU9<Doc> AB Thursday, August 24, 2023<Designer><Reviewer> 24 32<Title><Page Title>SizeDoc NumberRevDate: SheetofReviewerDesignerDepartmentProject
Page TitleBU9<Doc> AB Thursday, August 24, 2023<Designer><Reviewer> 24 32<Title><Page Title>
R186100KR0402-02015%1/16WJP5CONN3_HBB1037-L300D-8H123
D
G
S
U25DMN53D0L-7<Part Number>DGS
D
G
S
U22DMN53D0L-7<Part Number>DGS3 state outputU2174LVC1G125GV<Part Number>24513C26 0.1UFX7R 16V C0402-0201R15537.4K<Part Number>1%1/16WR382 301R0402-02011%1/16WR384499KR0805_H261%<Part Number>
R387100KR0402-02015%1/16W
JP6CONN3_HBB1037-L300D-8H123
D
G
S
U23DMN53D0L-7<Part Number>DGS
R383100KR0402-02015%1/16WR3814.7KR0402-02015%1/16WNI R3864.7KR0402-02015%1/16W
R38537.4K<Part Number>1%1/16W
D
G
S
U26DMN53D0L-7<Part Number>DGS
D
G
S
U24DMN53D0L-7<Part Number>DGSR154499KR0805_H261%<Part Number>PWRGD_P3V3_AUX_MB_BUF_NGPU_HSC_BUF_R_ENGPU_HSC_BUF_ENGPU_HSC_BUF_ENGPU_HSC1_BUF_EN_NGPU_HSC2_BUF_EN_N
PWRGD_P3V3_AUX_MB_BUF_NTP_P52V_HS1_ENGPU_HSC1_BUF_EN_NTP_P52V_HS2_ENGPU_HSC2_BUF_EN_N



5
5
4
4
3
3
2
2
1
1
D D
C C
B B
A A
I sat =32A at 25C, 26A at 100CSize = 10.85 * 10 mmDCR= 11.8 mohm
Output Voltage = 3.3V±5%Output Ripple & Noise < 30mVTransient Tolerance = 330mVTDC = 10.5AMax current = 10.5AOver-Current Protection =13.65A (1.3*Max)Current Step =5.25ASlew Rate = 2.5A/usWork frequency = 600KHZEfficiency > 85% @TDC
Design specification
P3V3 AUX
PC54 need change to (270P) for TIC 2nd sourcePC55 need change to (2.2U) for TIC 2nd source
PR111 need change to 0ohm for TIC 2nd source
P12V_HPDB_PWRGD15 P3V3_HPDB_PG 15,26P3V3_AUXP12V_HPDBP3V3_AUX
SizeDoc NumberRevDate: SheetofReviewerDesignerDepartmentProject
Page TitleBU9<Doc> AB Friday, August 25, 2023<Designer><Reviewer> 25 32<Title><Page Title>SizeDoc NumberRevDate: SheetofReviewerDesignerDepartmentProject
Page TitleBU9<Doc> AB Friday, August 25, 2023<Designer><Reviewer> 25 32<Title><Page Title>SizeDoc NumberRevDate: SheetofReviewerDesignerDepartmentProject
Page TitleBU9<Doc> AB Friday, August 25, 2023<Designer><Reviewer> 25 32<Title><Page Title>
PC61822UFPC510.1UF25V10%<Part Number>C0402-0201X7RPR1134.87K1/16W1%R0402-0201<Part Number>R394 0R0402-02015%1/16WPC5022UFPL1100NH<Part Number>L_HCBS4545_4-5X4-521PC5622UFX6SC0805_H5720%16V<Part Number>PU5MPQ8633AGLE-C807-Z<Part Number>VIN110PGOOD9PGND11_18EN8BST1FB7AGND2VCC19RGND6SW20TRK_REF5MODE4CS3VIN221PC530.1UF25V10%C0402-0201<Part Number>X7RPC551UF25V10%C0402-0201X6S<Part Number>PC54 56PF50V5%<Part Number>C0402-0201NPOPC601UF25V10%C0402X6S<Part Number>+PC138270UF12PC5922UF<Part Number>R393100K1/16W1%R0402-0201<Part Number>NIPC5822UFPR112 56K1/16W 1%R0402-0201<Part Number>PC61722UFR392681K1/16W1%R0402<Part Number>NI PC4822UFPC5722UFPR111 2.21/16W1%R0402-0201<Part Number>PR11010K1/16W1%R0402-0201<Part Number>PC520.1UF25V10%<Part Number>C0402-0201X7RPL2 2.2UH<Part Number>21PR11412.4K1/16W1%R0402-0201<Part Number>+PC137220UF<Part Number>12R5900 0R0402-02015%1/16WPC4922UFSW_P3V3_HPDB_FLTP3V3_HPDB_PG_RSW_P3V3_HPDB_BTSW_P3V3_HPDB_BT_RP3V3_HPDB_ENSW_P3V3_HPDB_PHP3V3_HPDB_VCCP3V3_HPDB_FBP3V3_HPDB_REFP3V3_HPDB_CS



5
5
4
4
3
3
2
2
1
1
D D
C C
B B
A A
P12V CURRENT LIMIT
Current=0.77A(max)OCP= 1A
R5921
U32 optional BOM
R5919
R5918
R5920
C98
MP5025A/
MP5022A
Pop
De-pop
Pop
De-pop
De-pop
RS31312
Pop
MP5025C/
MP5022C
Pop
De-pop
De-pop
Pop Pop
Pop
De-pop
Pop
De-pop
P3V3_HPDB_PG15,25PWRGD_P12V_FAN_LED 12FAN_PWR_EN_BUF15,17P12V_HPDBP3V3_AUXP12V_FAN_LEDP12V_HPDBP3V3_AUXP3V3_AUX
SizeDoc NumberRevDate: SheetofReviewerDesignerDepartmentProject
Page TitleBU9<Doc> AC Thursday, August 24, 2023<Designer><Reviewer> 26 32<Title><Page Title>SizeDoc NumberRevDate: SheetofReviewerDesignerDepartmentProject
Page TitleBU9<Doc> AC Thursday, August 24, 2023<Designer><Reviewer> 26 32<Title><Page Title>SizeDoc NumberRevDate: SheetofReviewerDesignerDepartmentProject
Page TitleBU9<Doc> AC Thursday, August 24, 2023<Designer><Reviewer> 26 32<Title><Page Title>
R5917 1K1% R0402-0201<Part Number>C960.1UFX7R25VC0402<Part Number>R592510K1%R0402-0201<Part Number>R592646.4K1%R0402-0201<Part Number>R5923130K<Part Number>1%R0402-0201R5940 0R0402-02015%1/16WU4074LVC1G08W5-7A1B2GND3Y4VCC5 C982.2UFX7R16VC0603_H40<Part Number>D4SMBJ14A<Part Number>ACC100100NF50V<Part Number>X7RC0402-0201R592420K1%1/16W<Part Number>R0402-0201R59181001%R0402<Part Number>NIC990.047UFX7R25VC0402-0201<Part Number>U38MP5022CGQV-Z<Part Number>VOUT_2020VIN_21_2221_22VOUT_1919VOUT_1818VOUT_1717VOUT_1616VOUT_1515VOUT_1414AVIN12VOUT_1313OV11PG10FLTB9IMON8VIN_2323VIN_2424VIN_2525VIN_2626EN1LOADEN2ENTM3TIMER4ISET5SS6GND7C1030.1UF10%16VC0402-0201X7RR591610K1%R0402-0201<Part Number>R5919120K<Part Number>R04021%R5941 0R0402-02015%1/16WD5B340A-13-F<Part Number>ACR592171.5K1%R0402<Part Number>NIC101560PF50VX7RC0402-0201C941UFX6S25VC0402<Part Number>R592049.91%<Part Number>R0603C970.22UFX7R25VC0402-0201<Part Number>C9510UFX6S25VC0805_H61<Part Number>R5930 0R0402-02015%1/16WR5922 10K1% R0402-0201<Part Number>PWRGD_P12V_FAN_LED_RP12V_LED_EN_RP12V_LED_PDP12V_LED_TIMERP12V_LED_FBP12V_LED_PDP12V_LED_ISETP12V_LED_SSP12V_LED_FLTBP12V_LED_IMONP12V_LED_ISET_RP12V_LED_EN_BUFFAN_PWR_EN_BUF_RP3V3_HPDB_PG_R1



5
5
4
4
3
3
2
2
1
1
D D
C C
B B
A A
PR483 (5.9K) for LTC4287      (2.21K) for ADM1272PR482 (4.42K) for LTC4287      (1.65K) for ADM1272
CO-LAYOUT
CO-LAYOUT
46V~52V.
Power team Dubug Header
PR479 PR315 change to (0.2mohm) for LTC4287VPN:LR2725-24R0002F1
46V~52V.
P52V_HS1_4287_GATE_R20P52V_HS1_1272_GATE21P52V_HS1_4287_GATE2_R20P52V_HS1_UVLO_EN 20,21P52V_HS1_OV 20,21P52V_HS1_TEMP20P52V_HS1_TEMPP21P52V_HS1_TEMPN21GPU_HSC1_BUF_EN24 SMB_P52V_PDB_SDA 7,20,21,22,23SMB_P52V_PDB_SCL 7,20,21,22,23P52V_HS_1272_S_P21P52V_HS_1272_S_N 21P52V_HS_4287_S1P 20P52V_HS_4287_S1N20P52V_HS_4287_S2P 20P52V_HS_4287_S2N20P52V_HS1_Drain_2 27P52V_HS_4287_ADC_P20P52V_HS_4287_ADC_N 20P52V_HS1_Drain_1 27P52V_HS1_Drain_1 27P52V_HS1_Drain_227
P52V_1_BUSBAR16P52V_HS1_EN 18,20,21FM_HS1_EN_BUSBAR_BUF 12FM_HS1_EN_FUSE_BUF 12
P52V_1GND_FIELD_SIGNALGND_FIELD_SIGNALP52V_1P52V_HS1
P52V_1_FUSE_1P52V_1_FUSE_1P52V_1P3V3_ANDP3V3_ANDP3V3_AUXP3V3_AUXP3V3_AUXP3V3_AUXSizeDoc NumberRevDate: SheetofReviewerDesignerDepartmentProject
Page TitleBU9<Doc> AC Friday, August 25, 2023<Designer><Reviewer> 27 32<Title><Page Title>SizeDoc NumberRevDate: SheetofReviewerDesignerDepartmentProject
Page TitleBU9<Doc> AC Friday, August 25, 2023<Designer><Reviewer> 27 32<Title><Page Title>SizeDoc NumberRevDate: SheetofReviewerDesignerDepartmentProject
Page TitleBU9<Doc> AC Friday, August 25, 2023<Designer><Reviewer> 27 32<Title><Page Title>0.0003PR315<Part Number>4W1%R2725_4P2B1B2A1APR5864 2001/16WR0402-02011%<Part Number>NI
PQ34PSMN3R7-100BSE  <Part Number>DGS
U4374LVC1G07SE-7VCC5A2GND3Y4NC11 PR695910R0603_H241%<Part Number>HSC1_BOM2PR6966 100<Part Number>1%1/16W R0402HSC1_BOM1PQ37MMBT3904-7-FBECPR48095.3K<Part Number>R0805_H261%  FS520A/125V12PC5760.1UFC0402-0201<Part Number>25VX7RC690.01UF10%100VC0603
PR477 10R0603_H24 1%PR69561R0603_H241%<Part Number>HSC1_BOM1PR695810R0603_H241%<Part Number>HSC1_BOM2PR475 10R0603_H24 1%PR696210R0603_H241%<Part Number>HSC1_BOM1R5902174K1%R0805_H26<Part Number>PR69641R0603_H241%<Part Number>HSC1_BOM1R59424.7KR0402-02015%1/16WPR478 10R0603_H24 1%
R59434.7KR0402-02015%1/16W
PR474 10R0603_H24 1%PQ35PSMN3R7-100BSE  <Part Number>DGSPD760V/51.70A<Part Number>ACR5862 05%R0402-0201 1/16WHSC1_BOM1R586005%R0402-02011/16WHSC1_BOM2PR696110R0603_H241%<Part Number>HSC1_BOM2PR695410R0603_H241%<Part Number>HSC1_BOM1PR695710R0603_H241%<Part Number>HSC1_BOM1R590411.5K<Part Number>R0402-02011%
PQ32PSMN3R7-100BSE  <Part Number>DGS
R413 0R590195.3K<Part Number>R0805_H261%PR69631R0603_H241%<Part Number>HSC1_BOM1PD8B380-13-F<Part Number>ACPD960V/51.70A<Part Number>ACPR48195.3K<Part Number>R0805_H261%  PR7040 2001/16WR0402-02011%<Part Number>NI0.0003PR479<Part Number>4W1%R2725_4P2B1B2A1APR4821.65K1%R0402-0201<Part Number>PR69690HSC1_BOM1PR69551R0603_H241%<Part Number>HSC1_BOM1C910.1UF10%16VC0402-0201X7RU3474LVC1G08W5-7A1B2GND3Y4VCC5
PQ36PSMN3R7-100BSE  <Part Number>DGSPR16 10R0603_H24 1%C1040.1UFX7R16VC0402-020110%PR4730<Part Number>R0402-0201 5%
PR476 10R0603_H24 1%
R398174KR0805_H261%<Part Number>
R5863 05%R0402-0201 1/16WHSC1_BOM1PC5750.1UFC0402-0201<Part Number>25VX7RC900.01UF10%100VC0603R59038.45K1%1/16WR0402-0201<Part Number>
PQ33PSMN3R7-100BSE  <Part Number>DGS
C1050.1UFX7R16VC0402-020110%PR696510R0603_H241%<Part Number>HSC1_BOM1PR970<Part Number>R0402-0201 5%JP3CONN3_HBB1037-L300D-8H123R39911.5K<Part Number>1%1/16W
R586105%R0402-02011/16WHSC1_BOM2PR4832.21K1%<Part Number>R0402-0201U4274LVC1G07SE-7VCC5A2GND3Y4NC11 PR69680HSC1_BOM2
PQ6PSMN3R7-100BSE  <Part Number>DGSPR696010R0603_H241%<Part Number>HSC1_BOM2PR6967 0HSC1_BOM2
P52V_HS1_GATE1P52V_HS1_GATE1_RP52V_HS1_GATE2P52V_HS1_GATE3P52V_HS1_GATE4P52V_HS1_GATE2_RP52V_HS1_GATE5P52V_HS1_GATE6P52V_HS1_SENSE_P_R1P52V_HS1_SENSE_N_R1P52V_1_FUSE_1P52V_HS1_OVP52V_HS1_UVLO_ENP52V_HS1_SENSE_P_R2P52V_HS1_SENSE_N_R2P52V_HS1_TEMPP52V_HS1_TEMPPP52V_HS1_TEMP_RP52V_HS1_TEMPN_RFM_HS1_EN_FUSESMB_P52V_PDB_DEBUG_SDASMB_P52V_PDB_DEBUG_SCLFM_HS1_EN_BUSBARFM_HS1_EN_BUSBARFM_HS1_EN_FUSE



5
5
4
4
3
3
2
2
1
1
D D
C C
B B
A A
PR6980 (5.9K)  for LTC4287       (2.21K) for ADM1272PR6979 (4.42K) for LTC4287       (1.65K) for ADM1272
CO-LAYOUT
CO-LAYOUT
46V~52V.
PR6976 PR6989 change to (0.2mohm) for LTC4287
46V~52V.
P52V_HS2_4287_GATE_R22P52V_HS2_1272_GATE23P52V_HS2_4287_GATE2_R22P52V_HS2_UVLO_EN 22,23P52V_HS2_OV 22,23P52V_HS2_TEMP22P52V_HS2_TEMPP23P52V_HS2_TEMPN23GPU_HSC2_BUF_EN24 P52V_HS2_4287_S1P 22P52V_HS2_4287_S1N22P52V_HS2_1272_S_P23P52V_HS2_1272_S_N 23P52V_HS2_4287_S2P 22P52V_HS2_4287_S2N22P52V_HS2_Drain_2 28P52V_HS2_4287_ADC_N 22P52V_HS2_4287_ADC_P22P52V_HS2_Drain_1 28P52V_HS2_Drain_1 28P52V_HS2_Drain_228
P52V_2_BUSBAR16P52V_HS2_EN 19,22,23FM_HS2_EN_BUSBAR_BUF 12FM_HS2_EN_FUSE_BUF 12
P52V_2GND1_FIELD_SIGNALGND1_FIELD_SIGNALP52V_2P52V_HS2
P52V_2_FUSE_1P52V_2_FUSE_1P52V_2P3V3_2_ANDP3V3_2_ANDP3V3_AUXP3V3_AUXP3V3_AUXP3V3_AUXSizeDoc NumberRevDate: SheetofReviewerDesignerDepartmentProject
Page TitleBU9<Doc> AC Friday, August 25, 2023<Designer><Reviewer> 28 32<Title><Page Title>SizeDoc NumberRevDate: SheetofReviewerDesignerDepartmentProject
Page TitleBU9<Doc> AC Friday, August 25, 2023<Designer><Reviewer> 28 32<Title><Page Title>SizeDoc NumberRevDate: SheetofReviewerDesignerDepartmentProject
Page TitleBU9<Doc> AC Friday, August 25, 2023<Designer><Reviewer> 28 32<Title><Page Title>PQ44MMBT3904-7-FBECPR7041 2001/16WR0402-02011%<Part Number>NIPR697795.3K<Part Number>R0805_H261%  FS620A/125V12 0.0003PR69894W1%R2725_4P<Part Number>2B1B2A1APC5780.1UFC0402-0201<Part Number>25VX7R
R589711.5K<Part Number>1%1/16W
PR6973 10R0603_H24 1%PR69811R0603_H241%<Part Number>HSC1_BOM1PR698610R0603_H241%<Part Number>HSC1_BOM2U4474LVC1G07SE-7VCC5A2GND3Y4NC11
PR6971 10R0603_H24 1%PR698410R0603_H241%<Part Number>HSC1_BOM1PR6974 10R0603_H24 1%
U4574LVC1G07SE-7VCC5A2GND3Y4NC11R5906174K1%R0805_H26<Part Number>PR69871R0603_H241%<Part Number>HSC1_BOM1
PQ41PSMN3R7-100BSE  <Part Number>DGSPD1260V/51.70A<Part Number>ACR5865 05%R0402-0201 1/16WHSC1_BOM1R586605%R0402-02011/16WHSC1_BOM2PR699110R0603_H241%<Part Number>HSC1_BOM2
PR6970 10R0603_H24 1%PR699310R0603_H241%<Part Number>HSC1_BOM1PR698210R0603_H241%<Part Number>HSC1_BOM1PQ38PSMN3R7-100BSE  <Part Number>DGS
C880.01UF10%100V<Part Number>C0603
PD10B380-13-F<Part Number>ACPD1160V/51.70A<Part Number>ACR590811.5K<Part Number>R0402-02011%PR697895.3K<Part Number>R0805_H261%  PR69831R0603_H241%<Part Number>HSC1_BOM1PR69791.65K1%R0402-0201<Part Number>
PR69970HSC1_BOM1R59444.7KR0402-02015%1/16WR59454.7KR0402-02015%1/16W
PQ42PSMN3R7-100BSE  <Part Number>DGSPR6975 10R0603_H24 1%PR6972 10R0603_H24 1%R590595.3K<Part Number>R0805_H261%PR69921R0603_H241%<Part Number>HSC1_BOM1C930.1UF10%16VC0402-0201X7RU3574LVC1G08W5-7A1B2GND3Y4VCC5PC5770.1UFC0402-0201<Part Number>25VX7RPQ39PSMN3R7-100BSE  <Part Number>DGSR5868 05%R0402-0201 1/16WHSC1_BOM1PR698810R0603_H241%<Part Number>HSC1_BOM1C920.01UF10%100VC0603R59078.45K1%1/16WR0402-0201<Part Number>PR7039 2001/16WR0402-02011%<Part Number>NIR58960R0402-02015%<Part Number>
R586705%R0402-02011/16WHSC1_BOM2PR69802.21K1%<Part Number>R0402-0201R5893174KR0805_H261%<Part Number>PR69960HSC1_BOM2
PQ43PSMN3R7-100BSE  <Part Number>DGSPR698510R0603_H241%<Part Number>HSC1_BOM2PR6995 0HSC1_BOM20.0003PR69764W1%R2725_4P<Part Number>2B1B2A1AC1060.1UFX7R16VC0402-020110%
PQ40PSMN3R7-100BSE  <Part Number>DGSPR699010R0603_H241%<Part Number>HSC1_BOM2C1070.1UFX7R16VC0402-020110%PR6994 100<Part Number>1%1/16W R0402HSC1_BOM1
P52V_HS2_GATE1P52V_HS2_GATE1_RP52V_HS2_GATE2P52V_HS2_GATE3P52V_HS2_GATE4P52V_HS2_GATE2_RP52V_HS2_GATE5P52V_HS2_GATE6P52V_HS2_SENSE_P_R1P52V_HS2_SENSE_N_R1P52V_2_FUSE_1P52V_HS2_OVP52V_HS2_UVLO_ENP52V_HS2_SENSE_P_R2P52V_HS2_SENSE_N_R2P52V_HS2_TEMPP52V_HS2_TEMPPP52V_HS2_TEMP_RP52V_HS2_TEMPN_RFM_HS2_EN_FUSEFM_HS2_EN_BUSBARFM_HS2_EN_BUSBARFM_HS2_EN_FUSE



5
5
4
4
3
3
2
2
1
1
D D
C C
B B
A A
LOSS COUPON
5 inch trace 10 inch trace
SizeDoc NumberRevDate: SheetofReviewerDesignerDepartmentProject
Page TitleBU9<Doc> AB Thursday, August 24, 2023<Designer><Reviewer> 29 32<Title><Page Title>SizeDoc NumberRevDate: SheetofReviewerDesignerDepartmentProject
Page TitleBU9<Doc> AB Thursday, August 24, 2023<Designer><Reviewer> 29 32<Title><Page Title>SizeDoc NumberRevDate: SheetofReviewerDesignerDepartmentProject
Page TitleBU9<Doc> AB Thursday, August 24, 2023<Designer><Reviewer> 29 32<Title><Page Title>



5
5
4
4
3
3
2
2
1
1
D D
C C
B B
A A
DUMMY SYMBOLS
Quanta LOGO(TOP)Laser Mark(TOP) Laser Mark(BOT)
PB-E1WEEEPCBA_LABEL
CE UL
SN LABEL PN LABEL
vendor logo
SizeDoc NumberRevDate: SheetofReviewerDesignerDepartmentProject
Page TitleBU9<Doc> AB Thursday, August 24, 2023<Designer><Reviewer> 30 32<Title><Page Title>SizeDoc NumberRevDate: SheetofReviewerDesignerDepartmentProject
Page TitleBU9<Doc> AB Thursday, August 24, 2023<Designer><Reviewer> 30 32<Title><Page Title>SizeDoc NumberRevDate: SheetofReviewerDesignerDepartmentProject
Page TitleBU9<Doc> AB Thursday, August 24, 2023<Designer><Reviewer> 30 32<Title><Page Title>
ME_PART SymbolME3QUANTA_LOGO_7X26ME_PART SymbolME4SNLABEL_7X7ME_PART SymbolME5PCB_VENDOR_LOGO_15X8
ME_PART SymbolDM1PNLABEL_23-5X5ME_PART SymbolME1PB-E1_SMALLME_PART SymbolME2WEEE



5
5
4
4
3
3
2
2
1
1
D D
C C
B B
A A
SCREW HOLES
GOURD SCREW HOLE
HANDLE SCREW HOLE THUMB SCREW HOLE
Tooling Holes
NUT HOLE
SizeDoc NumberRevDate: SheetofReviewerDesignerDepartmentProject
Page TitleBU9<Doc> AB Thursday, August 24, 2023<Designer><Reviewer> 31 32<Title><Page Title>SizeDoc NumberRevDate: SheetofReviewerDesignerDepartmentProject
Page TitleBU9<Doc> AB Thursday, August 24, 2023<Designer><Reviewer> 31 32<Title><Page Title>SizeDoc NumberRevDate: SheetofReviewerDesignerDepartmentProject
Page TitleBU9<Doc> AB Thursday, August 24, 2023<Designer><Reviewer> 31 32<Title><Page Title>
H36HOLE_C10-16D6-4B10_OB7XC5B_NPBH4HOLE_C9D3_5B9_OB5XC4-5_NPM_SPD<Part Number>H15HOLE_C9D3_5B9_OB5XC4-5_NPM_SPD<Part Number>
H33HOLE_C8D4-22B8I6-02_RO7-02_NPT_RB
H37HOLE_C10-16D6-4B10_OB7XC5B_NPBH25HOLE_TOOLINGD125N_T2-0H21GNDHOLE_8PIN<Part Number>H11HOLE_C9D3_5B9_OB5XC4-5_NPM_SPD<Part Number>H7HOLE_C9D3_5B9_OB5XC4-5_NPM_SPD<Part Number>H22GNDHOLE_8PIN<Part Number>H26HOLE_TOOLINGD125N_T2-0H10HOLE_C9D3_5B9_OB5XC4-5_NPM_SPD<Part Number>H3HOLE_C9D3_5B9_OB5XC4-5_NPM_SPD<Part Number>H6HOLE_C9D3_5B9_OB5XC4-5_NPM_SPD<Part Number>H35HOLE_C8D4-22B8I6-02_RO7-02_NPT_RBH19HOLE_C10-16D6-4B10_OB7XC5B_NPBH27HOLE_TOOLINGD125N_T2-0H20HOLE_C10-16D6-4B10_OB7XC5B_NPBH24GNDHOLE_8PIN<Part Number>
H16HOLE_C9D3_5B9_OB5XC4-5_NPM_SPD<Part Number>H5HOLE_C9D3_5B9_OB5XC4-5_NPM_SPD<Part Number>H13HOLE_C9D3_5B9_OB5XC4-5_NPM_SPD<Part Number>H14HOLE_C9D3_5B9_OB5XC4-5_NPM_SPD<Part Number>H32HOLE_C8D4-22B8I6-02_RO7-02_NPT_RBH34HOLE_C8D4-22B8I6-02_RO7-02_NPT_RB
H8HOLE_C9D3_5B9_OB5XC4-5_NPM_SPD<Part Number>H1HOLE_C9D3_5B9_OB5XC4-5_NPM_SPD<Part Number>H12HOLE_C9D3_5B9_OB5XC4-5_NPM_SPD<Part Number>H2HOLE_C9D3_5B9_OB5XC4-5_NPM_SPD<Part Number>H23GNDHOLE_8PIN<Part Number>H9HOLE_C9D3_5B9_OB5XC4-5_NPM_SPD<Part Number>
TP_H32TP_H33TP_H34TP_H35



5
5
4
4
3
3
2
2
1
1
D D
C C
B B
A A
BOT
TOP
IN1
IN2
TDR SizeDoc NumberRevDate: SheetofReviewerDesignerDepartmentProject
Page TitleBU9<Doc> AA Thursday, August 24, 2023<Designer><Reviewer> 32 32<Title><Page Title>SizeDoc NumberRevDate: SheetofReviewerDesignerDepartmentProject
Page TitleBU9<Doc> AA Thursday, August 24, 2023<Designer><Reviewer> 32 32<Title><Page Title>SizeDoc NumberRevDate: SheetofReviewerDesignerDepartmentProject
Page TitleBU9<Doc> AA Thursday, August 24, 2023<Designer><Reviewer> 32 32<Title><Page Title>
J13TDR_3P_C85P67_141_100M_QGND1IO12IO23J10TDR_3P_C85P67_141_100M_QGND1IO12IO23
J14TDR_3P_C85P67_141_100M_QGND1IO12IO23J12TDR_3P_C85P67_141_100M_QGND1IO12IO23TDR_SE_50_OHM_TOPTDR_SE_50_OHM_IN1TDR_SE_50_OHM_IN2TDR_SE_50_OHM_BOT